(kicad_pcb
	(version 20260206)
	(generator "pcbnew")
	(generator_version "10.0")
	(general
		(thickness 1.6)
		(legacy_teardrops no)
	)
	(paper "A4")
	(title_block
		(title "panther-plus-userver — 13130-1b_20150205.brd")
		(comment 1 "Honey Badger (Wiwynn) / footprints 689-695 of 1509")
	)
	(layers
		(0 "F.Cu" signal "TOP")
		(4 "In1.Cu" signal "L2")
		(6 "In2.Cu" signal "L3")
		(8 "In3.Cu" signal "L4")
		(10 "In4.Cu" signal "L5")
		(12 "In5.Cu" signal "L6")
		(14 "In6.Cu" signal "L7")
		(16 "In7.Cu" signal "L8")
		(18 "In8.Cu" signal "L9")
		(20 "In9.Cu" signal "L10")
		(22 "In10.Cu" signal "L11")
		(2 "B.Cu" signal "BOTTOM")
		(9 "F.Adhes" user "F.Adhesive")
		(11 "B.Adhes" user "B.Adhesive")
		(13 "F.Paste" user "Package Geometry/Pastemask Top")
		(15 "B.Paste" user "Package Geometry/Pastemask Bottom")
		(5 "F.SilkS" user "Ref Des/Silkscreen Top")
		(7 "B.SilkS" user "Ref Des/Silkscreen Bottom")
		(1 "F.Mask" user "Board Geometry/Soldermask Top")
		(3 "B.Mask" user "Board Geometry/Soldermask Bottom")
		(17 "Dwgs.User" user "User.Drawings")
		(19 "Cmts.User" user "User.Comments")
		(21 "Eco1.User" user "User.Eco1")
		(23 "Eco2.User" user "User.Eco2")
		(25 "Edge.Cuts" user "Board Geometry/Outline")
		(27 "Margin" user)
		(31 "F.CrtYd" user "Package Geometry/Place Bound Top")
		(29 "B.CrtYd" user "Package Geometry/Place Bound Bottom")
		(35 "F.Fab" user "Ref Des/Assembly Top")
		(33 "B.Fab" user "Ref Des/Assembly Bottom")
	)
	(footprint ""
		(layer "F.Cu")
		(at 15.494 -21.4122 90)
		(property "Reference" "PSP1"
			(at 0 0 90)
			(layer "F.SilkS")
			(hide yes)
			(effects
				(font
					(size 1.27 1.27)
				)
			)
		)
		(property "Value" "COPPER-CLOSE-GP-U"
			(at 0.0762 -2.8702 90)
			(unlocked yes)
			(layer "F.Fab")
			(hide yes)
			(effects
				(font
					(size 1.016 1.016)
					(thickness 0.1524)
				)
			)
		)
		(property "Device Type" "CON2C-U"
			(at 0.0762 -4.3942 90)
			(unlocked yes)
			(layer "F.Fab")
			(hide yes)
			(effects
				(font
					(size 1.016 1.016)
					(thickness 0.1524)
				)
			)
		)
		(duplicate_pad_numbers_are_jumpers no)
		(fp_rect
			(start -0.9398 0.9652)
			(end 0.9398 -0.9652)
			(stroke
				(width 0)
				(type default)
			)
			(fill no)
			(layer "F.CrtYd")
		)
		(fp_rect
			(start -0.9398 0.9652)
			(end 0.9398 -0.9652)
			(stroke
				(width 0)
				(type default)
			)
			(fill no)
			(layer "F.Fab")
		)
		(pad "1" smd custom
			(at 0 -0.5334 90)
			(size 0.17145 0.17145)
			(layers "F.Cu" "F.Mask" "F.Paste")
			(net "GND")
			(options
				(clearance outline)
				(anchor circle)
			)
			(primitives
				(gr_poly
					(pts
						(xy -0.127 0.3429) (xy -0.127 0.1651) (xy -0.635 -0.3429) (xy 0.635 -0.3429) (xy 0.127 0.1651)
						(xy 0.127 0.3429)
					)
					(width 0)
					(fill yes)
				)
			)
		)
		(pad "2" smd custom
			(at 0 0.5334 90)
			(size 0.17145 0.17145)
			(layers "F.Cu" "F.Mask" "F.Paste")
			(net "AGND_P1V0")
			(options
				(clearance outline)
				(anchor circle)
			)
			(primitives
				(gr_poly
					(pts
						(xy -0.635 0.3429) (xy -0.127 -0.1651) (xy -0.127 -0.3429) (xy 0.127 -0.3429) (xy 0.127 -0.1651)
						(xy 0.635 0.3429)
					)
					(width 0)
					(fill yes)
				)
			)
		)
	)
	(footprint ""
		(layer "F.Cu")
		(at 72.136 -55.626 -90)
		(property "Reference" "C70"
			(at 0 0 270)
			(layer "F.SilkS")
			(hide yes)
			(effects
				(font
					(size 1.27 1.27)
				)
			)
		)
		(property "Value" "SCD1U16V2KX-3GP"
			(at 1.1811 -2.7051 270)
			(unlocked yes)
			(layer "F.Fab")
			(hide yes)
			(effects
				(font
					(size 1.016 1.016)
					(thickness 0.1524)
				)
			)
		)
		(property "Device Type" "C402H22"
			(at 1.1811 -4.2291 270)
			(unlocked yes)
			(layer "F.Fab")
			(hide yes)
			(effects
				(font
					(size 1.016 1.016)
					(thickness 0.1524)
				)
			)
		)
		(duplicate_pad_numbers_are_jumpers no)
		(fp_rect
			(start -0.381 0.7366)
			(end 0.381 -0.7366)
			(stroke
				(width 0)
				(type default)
			)
			(fill no)
			(layer "F.CrtYd")
		)
		(fp_rect
			(start -0.381 0.7366)
			(end 0.381 -0.7366)
			(stroke
				(width 0)
				(type default)
			)
			(fill no)
			(layer "F.Fab")
		)
		(pad "1" smd custom
			(at 0 -0.4572 270)
			(size 0.1143 0.1143)
			(layers "F.Cu" "F.Mask" "F.Paste")
			(net "P1V0_SENSE")
			(options
				(clearance outline)
				(anchor circle)
			)
			(primitives
				(gr_poly
					(pts
						(arc
							(start -0.254 -0.1778)
							(mid -0.239121 -0.213721)
							(end -0.2032 -0.2286)
						)
						(arc
							(start 0.2032 -0.2286)
							(mid 0.239121 -0.213721)
							(end 0.254 -0.1778)
						)
						(arc
							(start 0.254 0.1778)
							(mid 0.239121 0.213721)
							(end 0.2032 0.2286)
						)
						(arc
							(start -0.2032 0.2286)
							(mid -0.239121 0.213721)
							(end -0.254 0.1778)
						)
					)
					(width 0)
					(fill yes)
				)
			)
		)
		(pad "2" smd custom
			(at 0 0.4572 270)
			(size 0.1143 0.1143)
			(layers "F.Cu" "F.Mask" "F.Paste")
			(net "GND")
			(options
				(clearance outline)
				(anchor circle)
			)
			(primitives
				(gr_poly
					(pts
						(arc
							(start -0.254 -0.1778)
							(mid -0.239121 -0.213721)
							(end -0.2032 -0.2286)
						)
						(arc
							(start 0.2032 -0.2286)
							(mid 0.239121 -0.213721)
							(end 0.254 -0.1778)
						)
						(arc
							(start 0.254 0.1778)
							(mid 0.239121 0.213721)
							(end 0.2032 0.2286)
						)
						(arc
							(start -0.2032 0.2286)
							(mid -0.239121 0.213721)
							(end -0.254 0.1778)
						)
					)
					(width 0)
					(fill yes)
				)
			)
		)
	)
	(footprint ""
		(layer "F.Cu")
		(at 44.323 -25.7302 180)
		(property "Reference" "C208"
			(at 0 0 180)
			(layer "F.SilkS")
			(hide yes)
			(effects
				(font
					(size 1.27 1.27)
				)
			)
		)
		(property "Value" "SCD1U10V2KX-5GP"
			(at 1.1811 -2.7051 180)
			(unlocked yes)
			(layer "F.Fab")
			(hide yes)
			(effects
				(font
					(size 1.016 1.016)
					(thickness 0.1524)
				)
			)
		)
		(property "Device Type" "C402H22"
			(at 1.1811 -4.2291 180)
			(unlocked yes)
			(layer "F.Fab")
			(hide yes)
			(effects
				(font
					(size 1.016 1.016)
					(thickness 0.1524)
				)
			)
		)
		(duplicate_pad_numbers_are_jumpers no)
		(fp_rect
			(start -0.381 0.7366)
			(end 0.381 -0.7366)
			(stroke
				(width 0)
				(type default)
			)
			(fill no)
			(layer "F.CrtYd")
		)
		(fp_rect
			(start -0.381 0.7366)
			(end 0.381 -0.7366)
			(stroke
				(width 0)
				(type default)
			)
			(fill no)
			(layer "F.Fab")
		)
		(pad "1" smd custom
			(at 0 -0.4572 180)
			(size 0.1143 0.1143)
			(layers "F.Cu" "F.Mask" "F.Paste")
			(net "P3V3_VDD_CLKBUFF")
			(options
				(clearance outline)
				(anchor circle)
			)
			(primitives
				(gr_poly
					(pts
						(arc
							(start -0.254 -0.1778)
							(mid -0.239121 -0.213721)
							(end -0.2032 -0.2286)
						)
						(arc
							(start 0.2032 -0.2286)
							(mid 0.239121 -0.213721)
							(end 0.254 -0.1778)
						)
						(arc
							(start 0.254 0.1778)
							(mid 0.239121 0.213721)
							(end 0.2032 0.2286)
						)
						(arc
							(start -0.2032 0.2286)
							(mid -0.239121 0.213721)
							(end -0.254 0.1778)
						)
					)
					(width 0)
					(fill yes)
				)
			)
		)
		(pad "2" smd custom
			(at 0 0.4572 180)
			(size 0.1143 0.1143)
			(layers "F.Cu" "F.Mask" "F.Paste")
			(net "GND")
			(options
				(clearance outline)
				(anchor circle)
			)
			(primitives
				(gr_poly
					(pts
						(arc
							(start -0.254 -0.1778)
							(mid -0.239121 -0.213721)
							(end -0.2032 -0.2286)
						)
						(arc
							(start 0.2032 -0.2286)
							(mid 0.239121 -0.213721)
							(end 0.254 -0.1778)
						)
						(arc
							(start 0.254 0.1778)
							(mid 0.239121 0.213721)
							(end 0.2032 0.2286)
						)
						(arc
							(start -0.2032 0.2286)
							(mid -0.239121 0.213721)
							(end -0.254 0.1778)
						)
					)
					(width 0)
					(fill yes)
				)
			)
		)
	)
	(footprint ""
		(layer "F.Cu")
		(at 74.4982 -41.148 180)
		(property "Reference" "C26"
			(at 0 0 180)
			(layer "F.SilkS")
			(hide yes)
			(effects
				(font
					(size 1.27 1.27)
				)
			)
		)
		(property "Value" "SC6P50V2CN-1GP"
			(at 1.1811 -2.7051 180)
			(unlocked yes)
			(layer "F.Fab")
			(hide yes)
			(effects
				(font
					(size 1.016 1.016)
					(thickness 0.1524)
				)
			)
		)
		(property "Device Type" "C402H22"
			(at 1.1811 -4.2291 180)
			(unlocked yes)
			(layer "F.Fab")
			(hide yes)
			(effects
				(font
					(size 1.016 1.016)
					(thickness 0.1524)
				)
			)
		)
		(duplicate_pad_numbers_are_jumpers no)
		(fp_rect
			(start -0.381 0.7366)
			(end 0.381 -0.7366)
			(stroke
				(width 0)
				(type default)
			)
			(fill no)
			(layer "F.CrtYd")
		)
		(fp_rect
			(start -0.381 0.7366)
			(end 0.381 -0.7366)
			(stroke
				(width 0)
				(type default)
			)
			(fill no)
			(layer "F.Fab")
		)
		(pad "1" smd custom
			(at 0 -0.4572 180)
			(size 0.1143 0.1143)
			(layers "F.Cu" "F.Mask" "F.Paste")
			(net "RTC_X1PAD")
			(options
				(clearance outline)
				(anchor circle)
			)
			(primitives
				(gr_poly
					(pts
						(arc
							(start -0.254 -0.1778)
							(mid -0.239121 -0.213721)
							(end -0.2032 -0.2286)
						)
						(arc
							(start 0.2032 -0.2286)
							(mid 0.239121 -0.213721)
							(end 0.254 -0.1778)
						)
						(arc
							(start 0.254 0.1778)
							(mid 0.239121 0.213721)
							(end 0.2032 0.2286)
						)
						(arc
							(start -0.2032 0.2286)
							(mid -0.239121 0.213721)
							(end -0.254 0.1778)
						)
					)
					(width 0)
					(fill yes)
				)
			)
		)
		(pad "2" smd custom
			(at 0 0.4572 180)
			(size 0.1143 0.1143)
			(layers "F.Cu" "F.Mask" "F.Paste")
			(net "GND")
			(options
				(clearance outline)
				(anchor circle)
			)
			(primitives
				(gr_poly
					(pts
						(arc
							(start -0.254 -0.1778)
							(mid -0.239121 -0.213721)
							(end -0.2032 -0.2286)
						)
						(arc
							(start 0.2032 -0.2286)
							(mid 0.239121 -0.213721)
							(end 0.254 -0.1778)
						)
						(arc
							(start 0.254 0.1778)
							(mid 0.239121 0.213721)
							(end 0.2032 0.2286)
						)
						(arc
							(start -0.2032 0.2286)
							(mid -0.239121 0.213721)
							(end -0.254 0.1778)
						)
					)
					(width 0)
					(fill yes)
				)
			)
		)
	)
	(footprint ""
		(layer "F.Cu")
		(at 70.612 -53.467 90)
		(property "Reference" "Q16"
			(at 0 0 90)
			(layer "F.SilkS")
			(hide yes)
			(effects
				(font
					(size 1.27 1.27)
				)
			)
		)
		(property "Value" "2N7002A-7-GP"
			(at -4.3561 -5.7912 90)
			(unlocked yes)
			(layer "F.Fab")
			(hide yes)
			(effects
				(font
					(size 1.016 1.016)
					(thickness 0.1524)
				)
			)
		)
		(property "Device Type" "SOT23DGS2D4H48"
			(at -4.3561 -7.3152 90)
			(unlocked yes)
			(layer "F.Fab")
			(hide yes)
			(effects
				(font
					(size 1.016 1.016)
					(thickness 0.1524)
				)
			)
		)
		(duplicate_pad_numbers_are_jumpers no)
		(fp_line
			(start 1.7145 -0.4445)
			(end -1.7145 -0.4445)
			(stroke
				(width 0.1524)
				(type default)
			)
			(layer "F.SilkS")
		)
		(fp_line
			(start -1.7145 -0.4445)
			(end -1.7145 0.4445)
			(stroke
				(width 0.1524)
				(type default)
			)
			(layer "F.SilkS")
		)
		(fp_line
			(start 1.7145 0.4445)
			(end 1.7145 -0.4445)
			(stroke
				(width 0.1524)
				(type default)
			)
			(layer "F.SilkS")
		)
		(fp_line
			(start -1.7145 0.4445)
			(end 1.7145 0.4445)
			(stroke
				(width 0.1524)
				(type default)
			)
			(layer "F.SilkS")
		)
		(fp_poly
			(pts
				(xy -1.4224 1.5621) (xy -1.4224 0.9017) (xy -1.7145 0.9017) (xy -1.7145 -0.9017) (xy -0.4699 -0.9017)
				(xy -0.4699 -1.5621) (xy 0.4699 -1.5621) (xy 0.4699 -0.9017) (xy 1.7145 -0.9017) (xy 1.7145 0.9017)
				(xy 1.4224 0.9017) (xy 1.4224 1.5621) (xy 0.4826 1.5621) (xy 0.4826 0.9017) (xy -0.4826 0.9017)
				(xy -0.4826 1.5621)
			)
			(stroke
				(width 0)
				(type default)
			)
			(fill no)
			(layer "F.CrtYd")
		)
		(fp_poly
			(pts
				(xy -1.4224 1.5621) (xy -1.4224 0.9017) (xy -1.7145 0.9017) (xy -1.7145 -0.9017) (xy -0.4699 -0.9017)
				(xy -0.4699 -1.5621) (xy 0.4699 -1.5621) (xy 0.4699 -0.9017) (xy 1.7145 -0.9017) (xy 1.7145 0.9017)
				(xy 1.4224 0.9017) (xy 1.4224 1.5621) (xy 0.4826 1.5621) (xy 0.4826 0.9017) (xy -0.4826 0.9017)
				(xy -0.4826 1.5621)
			)
			(stroke
				(width 0)
				(type default)
			)
			(fill no)
			(layer "F.Fab")
		)
		(pad "D" smd custom
			(at 0 -1.069086 90)
			(size 0.17145 0.17145)
			(layers "F.Cu" "F.Mask" "F.Paste")
			(net "SMBUS_SW_INV_D")
			(options
				(clearance outline)
				(anchor circle)
			)
			(primitives
				(gr_poly
					(pts
						(arc
							(start -0.1397 0.3683)
							(mid -0.283384 0.308784)
							(end -0.3429 0.1651)
						)
						(arc
							(start -0.3429 -0.1651)
							(mid -0.283384 -0.308784)
							(end -0.1397 -0.3683)
						)
						(arc
							(start 0.1397 -0.3683)
							(mid 0.283384 -0.308784)
							(end 0.3429 -0.1651)
						)
						(arc
							(start 0.3429 0.1651)
							(mid 0.283384 0.308784)
							(end 0.1397 0.3683)
						)
					)
					(width 0)
					(fill yes)
				)
			)
		)
		(pad "G" smd custom
			(at -0.94996 1.069086 90)
			(size 0.17145 0.17145)
			(layers "F.Cu" "F.Mask" "F.Paste")
			(net "SMBUS_SW_EN")
			(options
				(clearance outline)
				(anchor circle)
			)
			(primitives
				(gr_poly
					(pts
						(arc
							(start -0.1397 0.3683)
							(mid -0.283384 0.308784)
							(end -0.3429 0.1651)
						)
						(arc
							(start -0.3429 -0.1651)
							(mid -0.283384 -0.308784)
							(end -0.1397 -0.3683)
						)
						(arc
							(start 0.1397 -0.3683)
							(mid 0.283384 -0.308784)
							(end 0.3429 -0.1651)
						)
						(arc
							(start 0.3429 0.1651)
							(mid 0.283384 0.308784)
							(end 0.1397 0.3683)
						)
					)
					(width 0)
					(fill yes)
				)
			)
		)
		(pad "S" smd custom
			(at 0.94996 1.069086 90)
			(size 0.17145 0.17145)
			(layers "F.Cu" "F.Mask" "F.Paste")
			(net "GND")
			(options
				(clearance outline)
				(anchor circle)
			)
			(primitives
				(gr_poly
					(pts
						(arc
							(start -0.1397 0.3683)
							(mid -0.283384 0.308784)
							(end -0.3429 0.1651)
						)
						(arc
							(start -0.3429 -0.1651)
							(mid -0.283384 -0.308784)
							(end -0.1397 -0.3683)
						)
						(arc
							(start 0.1397 -0.3683)
							(mid 0.283384 -0.308784)
							(end 0.3429 -0.1651)
						)
						(arc
							(start 0.3429 0.1651)
							(mid 0.283384 0.308784)
							(end 0.1397 0.3683)
						)
					)
					(width 0)
					(fill yes)
				)
			)
		)
	)
	(footprint ""
		(layer "F.Cu")
		(at 169.926 -40.894 -90)
		(property "Reference" "PC210"
			(at 0 0 270)
			(layer "F.SilkS")
			(hide yes)
			(effects
				(font
					(size 1.27 1.27)
				)
			)
		)
		(property "Value" "SC22P50V2GN-GP"
			(at 1.8923 -1.2065 270)
			(unlocked yes)
			(layer "F.Fab")
			(hide yes)
			(effects
				(font
					(size 1.016 1.016)
					(thickness 0.1524)
				)
			)
		)
		(property "Device Type" "C402H22"
			(at 1.8923 -2.7305 270)
			(unlocked yes)
			(layer "F.Fab")
			(hide yes)
			(effects
				(font
					(size 1.016 1.016)
					(thickness 0.1524)
				)
			)
		)
		(duplicate_pad_numbers_are_jumpers no)
		(fp_rect
			(start -0.381 0.7366)
			(end 0.381 -0.7366)
			(stroke
				(width 0)
				(type default)
			)
			(fill no)
			(layer "F.CrtYd")
		)
		(fp_rect
			(start -0.381 0.7366)
			(end 0.381 -0.7366)
			(stroke
				(width 0)
				(type default)
			)
			(fill no)
			(layer "F.Fab")
		)
		(pad "1" smd custom
			(at 0 -0.4572 270)
			(size 0.1143 0.1143)
			(layers "F.Cu" "F.Mask" "F.Paste")
			(net "P2V5_STBY_OUT")
			(options
				(clearance outline)
				(anchor circle)
			)
			(primitives
				(gr_poly
					(pts
						(arc
							(start -0.254 -0.1778)
							(mid -0.239121 -0.213721)
							(end -0.2032 -0.2286)
						)
						(arc
							(start 0.2032 -0.2286)
							(mid 0.239121 -0.213721)
							(end 0.254 -0.1778)
						)
						(arc
							(start 0.254 0.1778)
							(mid 0.239121 0.213721)
							(end 0.2032 0.2286)
						)
						(arc
							(start -0.2032 0.2286)
							(mid -0.239121 0.213721)
							(end -0.254 0.1778)
						)
					)
					(width 0)
					(fill yes)
				)
			)
		)
		(pad "2" smd custom
			(at 0 0.4572 270)
			(size 0.1143 0.1143)
			(layers "F.Cu" "F.Mask" "F.Paste")
			(net "P2V5_STBY_FB")
			(options
				(clearance outline)
				(anchor circle)
			)
			(primitives
				(gr_poly
					(pts
						(arc
							(start -0.254 -0.1778)
							(mid -0.239121 -0.213721)
							(end -0.2032 -0.2286)
						)
						(arc
							(start 0.2032 -0.2286)
							(mid 0.239121 -0.213721)
							(end 0.254 -0.1778)
						)
						(arc
							(start 0.254 0.1778)
							(mid 0.239121 0.213721)
							(end 0.2032 0.2286)
						)
						(arc
							(start -0.2032 0.2286)
							(mid -0.239121 0.213721)
							(end -0.254 0.1778)
						)
					)
					(width 0)
					(fill yes)
				)
			)
		)
	)
	(footprint ""
		(layer "F.Cu")
		(at 134.62 -15.367 -90)
		(property "Reference" "U30"
			(at 0 0 270)
			(layer "F.SilkS")
			(hide yes)
			(effects
				(font
					(size 1.27 1.27)
				)
			)
		)
		(property "Value" "2N7002DW-7F-GP"
			(at -2.5654 1.1049 270)
			(unlocked yes)
			(layer "F.Fab")
			(hide yes)
			(effects
				(font
					(size 1.016 1.016)
					(thickness 0.1524)
				)
			)
		)
		(property "Device Type" "SOT-363H44"
			(at -2.5654 -0.4191 270)
			(unlocked yes)
			(layer "F.Fab")
			(hide yes)
			(effects
				(font
					(size 1.016 1.016)
					(thickness 0.1524)
				)
			)
		)
		(duplicate_pad_numbers_are_jumpers no)
		(fp_poly
			(pts
				(xy -0.6731 1.4351) (xy -0.9779 1.7399) (xy -0.381 1.7399) (xy -0.3683 1.7399) (xy -0.381 1.7272)
			)
			(stroke
				(width 0)
				(type default)
			)
			(fill yes)
			(layer "F.SilkS")
		)
		(fp_poly
			(pts
				(xy 1.2573 0.8763) (xy 1.2573 -0.8763) (xy 0.9525 -0.8763) (xy 0.9525 -1.4351) (xy -0.9525 -1.4351)
				(xy -0.9525 -0.8763) (xy -1.2573 -0.8763) (xy -1.2573 0.8763) (xy -0.9525 0.8763) (xy -0.9525 1.4351)
				(xy 0.9525 1.4351) (xy 0.9525 0.8763)
			)
			(stroke
				(width 0)
				(type default)
			)
			(fill no)
			(layer "F.CrtYd")
		)
		(fp_poly
			(pts
				(xy 1.2573 0.8763) (xy 1.2573 -0.8763) (xy 0.9525 -0.8763) (xy 0.9525 -1.4351) (xy -0.9525 -1.4351)
				(xy -0.9525 -0.8763) (xy -1.2573 -0.8763) (xy -1.2573 0.8763) (xy -0.9525 0.8763) (xy -0.9525 1.4351)
				(xy 0.9525 1.4351) (xy 0.9525 0.8763)
			)
			(stroke
				(width 0)
				(type default)
			)
			(fill no)
			(layer "F.Fab")
		)
		(pad "1" smd rect
			(at -0.65024 0.8255 270)
			(size 0.3556 0.9652)
			(layers "F.Cu" "F.Mask" "F.Paste")
			(net "GND")
		)
		(pad "2" smd rect
			(at 0 0.8255 270)
			(size 0.3556 0.9652)
			(layers "F.Cu" "F.Mask" "F.Paste")
			(net "HOST_R_RSTBTN#")
		)
		(pad "3" smd rect
			(at 0.65024 0.8255 270)
			(size 0.3556 0.9652)
			(layers "F.Cu" "F.Mask" "F.Paste")
			(net "HOST_LV_RSTBTN#")
		)
		(pad "4" smd rect
			(at 0.65024 -0.8255 270)
			(size 0.3556 0.9652)
			(layers "F.Cu" "F.Mask" "F.Paste")
			(net "GND")
		)
		(pad "5" smd rect
			(at 0 -0.8255 270)
			(size 0.3556 0.9652)
			(layers "F.Cu" "F.Mask" "F.Paste")
			(net "HOST_LV_D_RSTBTN#")
		)
		(pad "6" smd rect
			(at -0.65024 -0.8255 270)
			(size 0.3556 0.9652)
			(layers "F.Cu" "F.Mask" "F.Paste")
			(net "HOST_LV_D_RSTBTN#")
		)
	)
)
